(kicad_pcb
	(version 20260206)
	(generator "pcbnew")
	(generator_version "10.0")
	(general
		(thickness 1.6)
		(legacy_teardrops no)
	)
	(paper "A4")
	(title_block
		(title "01162023_DA0F0TEBIF0_F0T_Expander_BD_F_brd_V02_OCP.brd")
		(comment 1 "Grand Teton / footprints 3704-3711 of 9728")
	)
	(layers
		(0 "F.Cu" signal "TOP")
		(4 "In1.Cu" signal "GND")
		(6 "In2.Cu" signal "VCC")
		(8 "In3.Cu" signal "VCC1")
		(10 "In4.Cu" signal "GND1")
		(12 "In5.Cu" signal "IN1")
		(14 "In6.Cu" signal "GND2")
		(16 "In7.Cu" signal "IN2")
		(18 "In8.Cu" signal "GND3")
		(20 "In9.Cu" signal "IN3")
		(22 "In10.Cu" signal "GND4")
		(24 "In11.Cu" signal "IN4")
		(26 "In12.Cu" signal "GND5")
		(28 "In13.Cu" signal "IN5")
		(30 "In14.Cu" signal "GND6")
		(32 "In15.Cu" signal "IN6")
		(34 "In16.Cu" signal "GND7")
		(2 "B.Cu" signal "BOTTOM")
		(9 "F.Adhes" user "F.Adhesive")
		(11 "B.Adhes" user "B.Adhesive")
		(13 "F.Paste" user "Package Geometry/Pastemask Top")
		(15 "B.Paste" user "Package Geometry/Pastemask Bottom")
		(5 "F.SilkS" user "Ref Des/Silkscreen Top")
		(7 "B.SilkS" user "Ref Des/Silkscreen Bottom")
		(1 "F.Mask" user "Board Geometry/Soldermask Top")
		(3 "B.Mask" user "Board Geometry/Soldermask Bottom")
		(17 "Dwgs.User" user "User.Drawings")
		(19 "Cmts.User" user "User.Comments")
		(21 "Eco1.User" user "User.Eco1")
		(23 "Eco2.User" user "User.Eco2")
		(25 "Edge.Cuts" user "Board Geometry/Outline")
		(27 "Margin" user)
		(31 "F.CrtYd" user "Package Geometry/Place Bound Top")
		(29 "B.CrtYd" user "Package Geometry/Place Bound Bottom")
		(35 "F.Fab" user "Ref Des/Assembly Top")
		(33 "B.Fab" user "Ref Des/Assembly Bottom")
	)
	(footprint ""
		(layer "F.Cu")
		(at 243.248434 -250.759722 90)
		(property "Reference" "R6238"
			(at 0 0 90)
			(layer "F.SilkS")
			(hide yes)
			(effects
				(font
					(size 1.27 1.27)
				)
			)
		)
		(property "Value" ""
			(at 0 0 90)
			(layer "F.Fab")
			(effects
				(font
					(size 1.27 1.27)
				)
			)
		)
		(duplicate_pad_numbers_are_jumpers no)
		(fp_line
			(start 0.7874 -0.4064)
			(end 0.7874 0.4064)
			(stroke
				(width 0.1524)
				(type default)
			)
			(layer "F.SilkS")
		)
		(fp_line
			(start -0.7874 -0.4064)
			(end 0.7874 -0.4064)
			(stroke
				(width 0.1524)
				(type default)
			)
			(layer "F.SilkS")
		)
		(fp_line
			(start 0.7874 0.4064)
			(end -0.7874 0.4064)
			(stroke
				(width 0.1524)
				(type default)
			)
			(layer "F.SilkS")
		)
		(fp_line
			(start -0.7874 0.4064)
			(end -0.7874 -0.4064)
			(stroke
				(width 0.1524)
				(type default)
			)
			(layer "F.SilkS")
		)
		(fp_line
			(start -0.12065 -0.305054)
			(end -0.12065 -0.2794)
			(stroke
				(width 0.1)
				(type default)
			)
			(layer "F.Fab")
		)
		(fp_line
			(start -0.67945 -0.305054)
			(end -0.12065 -0.305054)
			(stroke
				(width 0.1)
				(type default)
			)
			(layer "F.Fab")
		)
		(fp_line
			(start 0.67945 -0.3048)
			(end 0.67945 0.3048)
			(stroke
				(width 0.1)
				(type default)
			)
			(layer "F.Fab")
		)
		(fp_line
			(start 0.12065 -0.3048)
			(end 0.67945 -0.3048)
			(stroke
				(width 0.1)
				(type default)
			)
			(layer "F.Fab")
		)
		(fp_line
			(start 0.12065 -0.2794)
			(end 0.12065 -0.3048)
			(stroke
				(width 0.1)
				(type default)
			)
			(layer "F.Fab")
		)
		(fp_line
			(start -0.12065 -0.2794)
			(end 0.12065 -0.2794)
			(stroke
				(width 0.1)
				(type default)
			)
			(layer "F.Fab")
		)
		(fp_line
			(start 0.120396 0.2794)
			(end -0.12065 0.2794)
			(stroke
				(width 0.1)
				(type default)
			)
			(layer "F.Fab")
		)
		(fp_line
			(start -0.12065 0.2794)
			(end -0.12065 0.3048)
			(stroke
				(width 0.1)
				(type default)
			)
			(layer "F.Fab")
		)
		(fp_line
			(start 0.67945 0.3048)
			(end 0.120396 0.3048)
			(stroke
				(width 0.1)
				(type default)
			)
			(layer "F.Fab")
		)
		(fp_line
			(start 0.120396 0.3048)
			(end 0.120396 0.2794)
			(stroke
				(width 0.1)
				(type default)
			)
			(layer "F.Fab")
		)
		(fp_line
			(start -0.12065 0.3048)
			(end -0.67945 0.3048)
			(stroke
				(width 0.1)
				(type default)
			)
			(layer "F.Fab")
		)
		(fp_line
			(start -0.67945 0.3048)
			(end -0.67945 -0.305054)
			(stroke
				(width 0.1)
				(type default)
			)
			(layer "F.Fab")
		)
		(pad "1" smd circle
			(at -0.40005 0 90)
			(size 0 0)
			(layers "F.Cu" "F.Mask" "F.Paste")
			(net "BIC_RECOVER_IOEXP_A1")
		)
		(pad "2" smd circle
			(at 0.40005 0 90)
			(size 0 0)
			(layers "F.Cu" "F.Mask" "F.Paste")
			(net "GND")
		)
	)
	(footprint ""
		(layer "F.Cu")
		(at 338.074 -155.702 180)
		(property "Reference" "R4816"
			(at 0 0 180)
			(layer "F.SilkS")
			(hide yes)
			(effects
				(font
					(size 1.27 1.27)
				)
			)
		)
		(property "Value" ""
			(at 0 0 180)
			(layer "F.Fab")
			(effects
				(font
					(size 1.27 1.27)
				)
			)
		)
		(duplicate_pad_numbers_are_jumpers no)
		(fp_line
			(start 0.7874 0.4064)
			(end -0.7874 0.4064)
			(stroke
				(width 0.1524)
				(type default)
			)
			(layer "F.SilkS")
		)
		(fp_line
			(start 0.7874 -0.4064)
			(end 0.7874 0.4064)
			(stroke
				(width 0.1524)
				(type default)
			)
			(layer "F.SilkS")
		)
		(fp_line
			(start -0.7874 0.4064)
			(end -0.7874 -0.4064)
			(stroke
				(width 0.1524)
				(type default)
			)
			(layer "F.SilkS")
		)
		(fp_line
			(start -0.7874 -0.4064)
			(end 0.7874 -0.4064)
			(stroke
				(width 0.1524)
				(type default)
			)
			(layer "F.SilkS")
		)
		(fp_line
			(start 0.67945 0.3048)
			(end 0.120396 0.3048)
			(stroke
				(width 0.1)
				(type default)
			)
			(layer "F.Fab")
		)
		(fp_line
			(start 0.67945 -0.3048)
			(end 0.67945 0.3048)
			(stroke
				(width 0.1)
				(type default)
			)
			(layer "F.Fab")
		)
		(fp_line
			(start 0.12065 -0.2794)
			(end 0.12065 -0.3048)
			(stroke
				(width 0.1)
				(type default)
			)
			(layer "F.Fab")
		)
		(fp_line
			(start 0.12065 -0.3048)
			(end 0.67945 -0.3048)
			(stroke
				(width 0.1)
				(type default)
			)
			(layer "F.Fab")
		)
		(fp_line
			(start 0.120396 0.3048)
			(end 0.120396 0.2794)
			(stroke
				(width 0.1)
				(type default)
			)
			(layer "F.Fab")
		)
		(fp_line
			(start 0.120396 0.2794)
			(end -0.12065 0.2794)
			(stroke
				(width 0.1)
				(type default)
			)
			(layer "F.Fab")
		)
		(fp_line
			(start -0.12065 0.3048)
			(end -0.67945 0.3048)
			(stroke
				(width 0.1)
				(type default)
			)
			(layer "F.Fab")
		)
		(fp_line
			(start -0.12065 0.2794)
			(end -0.12065 0.3048)
			(stroke
				(width 0.1)
				(type default)
			)
			(layer "F.Fab")
		)
		(fp_line
			(start -0.12065 -0.2794)
			(end 0.12065 -0.2794)
			(stroke
				(width 0.1)
				(type default)
			)
			(layer "F.Fab")
		)
		(fp_line
			(start -0.12065 -0.305054)
			(end -0.12065 -0.2794)
			(stroke
				(width 0.1)
				(type default)
			)
			(layer "F.Fab")
		)
		(fp_line
			(start -0.67945 0.3048)
			(end -0.67945 -0.305054)
			(stroke
				(width 0.1)
				(type default)
			)
			(layer "F.Fab")
		)
		(fp_line
			(start -0.67945 -0.305054)
			(end -0.12065 -0.305054)
			(stroke
				(width 0.1)
				(type default)
			)
			(layer "F.Fab")
		)
		(pad "1" smd circle
			(at -0.40005 0 180)
			(size 0 0)
			(layers "F.Cu" "F.Mask" "F.Paste")
			(net "PRSNT_SSD13_FPGA_PCA9555_N")
		)
		(pad "2" smd circle
			(at 0.40005 0 180)
			(size 0 0)
			(layers "F.Cu" "F.Mask" "F.Paste")
			(net "PRSNT_SSD13_FPGA_R_N")
		)
	)
	(footprint ""
		(layer "F.Cu")
		(at 262.353298 -284.990032)
		(property "Reference" "L127"
			(at 0 0 0)
			(layer "F.SilkS")
			(hide yes)
			(effects
				(font
					(size 1.27 1.27)
				)
			)
		)
		(property "Value" ""
			(at 0 0 0)
			(layer "F.Fab")
			(effects
				(font
					(size 1.27 1.27)
				)
			)
		)
		(duplicate_pad_numbers_are_jumpers no)
		(fp_line
			(start -1.63576 -0.8128)
			(end -1.63576 0.8128)
			(stroke
				(width 0.1524)
				(type default)
			)
			(layer "F.SilkS")
		)
		(fp_line
			(start -1.63576 -0.8128)
			(end 1.63576 -0.8128)
			(stroke
				(width 0.1524)
				(type default)
			)
			(layer "F.SilkS")
		)
		(fp_line
			(start 1.63576 -0.8128)
			(end 1.63576 0.8128)
			(stroke
				(width 0.1524)
				(type default)
			)
			(layer "F.SilkS")
		)
		(fp_line
			(start 1.63576 0.8128)
			(end -1.63576 0.8128)
			(stroke
				(width 0.1524)
				(type default)
			)
			(layer "F.SilkS")
		)
		(fp_line
			(start -1.56083 -0.738632)
			(end -1.56083 0.7366)
			(stroke
				(width 0.1)
				(type default)
			)
			(layer "F.Fab")
		)
		(fp_line
			(start -1.56083 0.7366)
			(end -1.524 0.7366)
			(stroke
				(width 0.1)
				(type default)
			)
			(layer "F.Fab")
		)
		(fp_line
			(start -1.524 0.7366)
			(end 1.524 0.7366)
			(stroke
				(width 0.1)
				(type default)
			)
			(layer "F.Fab")
		)
		(fp_line
			(start 1.524 0.7366)
			(end 1.560576 0.7366)
			(stroke
				(width 0.1)
				(type default)
			)
			(layer "F.Fab")
		)
		(fp_line
			(start 1.560576 -0.738632)
			(end -1.56083 -0.738632)
			(stroke
				(width 0.1)
				(type default)
			)
			(layer "F.Fab")
		)
		(fp_line
			(start 1.560576 0.7366)
			(end 1.560576 -0.738632)
			(stroke
				(width 0.1)
				(type default)
			)
			(layer "F.Fab")
		)
		(pad "1" smd rect
			(at -0.94996 0 180)
			(size 1.1176 1.3716)
			(layers "F.Cu" "F.Mask" "F.Paste")
			(net "P1V8_PLL0_PEX2")
		)
		(pad "2" smd rect
			(at 0.94996 0 180)
			(size 1.1176 1.3716)
			(layers "F.Cu" "F.Mask" "F.Paste")
			(net "PCEPLL7_VDDA18_PEX2")
		)
	)
	(footprint ""
		(layer "F.Cu")
		(at 139.817348 -350.098614 90)
		(property "Reference" "C2247"
			(at 0 0 90)
			(layer "F.SilkS")
			(hide yes)
			(effects
				(font
					(size 1.27 1.27)
				)
			)
		)
		(property "Value" ""
			(at 0 0 90)
			(layer "F.Fab")
			(effects
				(font
					(size 1.27 1.27)
				)
			)
		)
		(duplicate_pad_numbers_are_jumpers no)
		(fp_line
			(start 0.299974 -0.150114)
			(end 0.299974 0.150114)
			(stroke
				(width 0.1)
				(type default)
			)
			(layer "F.Fab")
		)
		(fp_line
			(start -0.299974 -0.150114)
			(end 0.299974 -0.150114)
			(stroke
				(width 0.1)
				(type default)
			)
			(layer "F.Fab")
		)
		(fp_line
			(start 0.299974 0.150114)
			(end -0.299974 0.150114)
			(stroke
				(width 0.1)
				(type default)
			)
			(layer "F.Fab")
		)
		(fp_line
			(start -0.299974 0.150114)
			(end -0.299974 -0.150114)
			(stroke
				(width 0.1)
				(type default)
			)
			(layer "F.Fab")
		)
		(pad "1" smd rect
			(at -0.2667 0 90)
			(size 0.3048 0.381)
			(layers "F.Cu" "F.Mask" "F.Paste")
			(net "P5E_PEX1_STN5_TX_DP<93>")
		)
		(pad "2" smd rect
			(at 0.2667 0 90)
			(size 0.3048 0.381)
			(layers "F.Cu" "F.Mask" "F.Paste")
			(net "P5E_PEX1_STN5_TX_C_DP<93>")
		)
	)
	(footprint ""
		(layer "F.Cu")
		(at 241.38509 -209.513678 90)
		(property "Reference" "R473"
			(at 0 0 90)
			(layer "F.SilkS")
			(hide yes)
			(effects
				(font
					(size 1.27 1.27)
				)
			)
		)
		(property "Value" ""
			(at 0 0 90)
			(layer "F.Fab")
			(effects
				(font
					(size 1.27 1.27)
				)
			)
		)
		(duplicate_pad_numbers_are_jumpers no)
		(fp_line
			(start 0.7874 -0.4064)
			(end 0.7874 0.4064)
			(stroke
				(width 0.1524)
				(type default)
			)
			(layer "F.SilkS")
		)
		(fp_line
			(start -0.7874 -0.4064)
			(end 0.7874 -0.4064)
			(stroke
				(width 0.1524)
				(type default)
			)
			(layer "F.SilkS")
		)
		(fp_line
			(start 0.7874 0.4064)
			(end -0.7874 0.4064)
			(stroke
				(width 0.1524)
				(type default)
			)
			(layer "F.SilkS")
		)
		(fp_line
			(start -0.7874 0.4064)
			(end -0.7874 -0.4064)
			(stroke
				(width 0.1524)
				(type default)
			)
			(layer "F.SilkS")
		)
		(fp_line
			(start -0.12065 -0.305054)
			(end -0.12065 -0.2794)
			(stroke
				(width 0.1)
				(type default)
			)
			(layer "F.Fab")
		)
		(fp_line
			(start -0.67945 -0.305054)
			(end -0.12065 -0.305054)
			(stroke
				(width 0.1)
				(type default)
			)
			(layer "F.Fab")
		)
		(fp_line
			(start 0.67945 -0.3048)
			(end 0.67945 0.3048)
			(stroke
				(width 0.1)
				(type default)
			)
			(layer "F.Fab")
		)
		(fp_line
			(start 0.12065 -0.3048)
			(end 0.67945 -0.3048)
			(stroke
				(width 0.1)
				(type default)
			)
			(layer "F.Fab")
		)
		(fp_line
			(start 0.12065 -0.2794)
			(end 0.12065 -0.3048)
			(stroke
				(width 0.1)
				(type default)
			)
			(layer "F.Fab")
		)
		(fp_line
			(start -0.12065 -0.2794)
			(end 0.12065 -0.2794)
			(stroke
				(width 0.1)
				(type default)
			)
			(layer "F.Fab")
		)
		(fp_line
			(start 0.120396 0.2794)
			(end -0.12065 0.2794)
			(stroke
				(width 0.1)
				(type default)
			)
			(layer "F.Fab")
		)
		(fp_line
			(start -0.12065 0.2794)
			(end -0.12065 0.3048)
			(stroke
				(width 0.1)
				(type default)
			)
			(layer "F.Fab")
		)
		(fp_line
			(start 0.67945 0.3048)
			(end 0.120396 0.3048)
			(stroke
				(width 0.1)
				(type default)
			)
			(layer "F.Fab")
		)
		(fp_line
			(start 0.120396 0.3048)
			(end 0.120396 0.2794)
			(stroke
				(width 0.1)
				(type default)
			)
			(layer "F.Fab")
		)
		(fp_line
			(start -0.12065 0.3048)
			(end -0.67945 0.3048)
			(stroke
				(width 0.1)
				(type default)
			)
			(layer "F.Fab")
		)
		(fp_line
			(start -0.67945 0.3048)
			(end -0.67945 -0.305054)
			(stroke
				(width 0.1)
				(type default)
			)
			(layer "F.Fab")
		)
		(pad "1" smd circle
			(at -0.40005 0 90)
			(size 0 0)
			(layers "F.Cu" "F.Mask" "F.Paste")
			(net "P5V_AUX")
		)
		(pad "2" smd circle
			(at 0.40005 0 90)
			(size 0 0)
			(layers "F.Cu" "F.Mask" "F.Paste")
			(net "P5V_AUX_SCALED")
		)
	)
	(footprint ""
		(layer "F.Cu")
		(at 217.254074 -210.176872)
		(property "Reference" "R5721"
			(at 0 0 0)
			(layer "F.SilkS")
			(hide yes)
			(effects
				(font
					(size 1.27 1.27)
				)
			)
		)
		(property "Value" ""
			(at 0 0 0)
			(layer "F.Fab")
			(effects
				(font
					(size 1.27 1.27)
				)
			)
		)
		(duplicate_pad_numbers_are_jumpers no)
		(fp_line
			(start -0.7874 -0.4064)
			(end 0.7874 -0.4064)
			(stroke
				(width 0.1524)
				(type default)
			)
			(layer "F.SilkS")
		)
		(fp_line
			(start -0.7874 0.4064)
			(end -0.7874 -0.4064)
			(stroke
				(width 0.1524)
				(type default)
			)
			(layer "F.SilkS")
		)
		(fp_line
			(start 0.7874 -0.4064)
			(end 0.7874 0.4064)
			(stroke
				(width 0.1524)
				(type default)
			)
			(layer "F.SilkS")
		)
		(fp_line
			(start 0.7874 0.4064)
			(end -0.7874 0.4064)
			(stroke
				(width 0.1524)
				(type default)
			)
			(layer "F.SilkS")
		)
		(fp_line
			(start -0.67945 -0.305054)
			(end -0.12065 -0.305054)
			(stroke
				(width 0.1)
				(type default)
			)
			(layer "F.Fab")
		)
		(fp_line
			(start -0.67945 0.3048)
			(end -0.67945 -0.305054)
			(stroke
				(width 0.1)
				(type default)
			)
			(layer "F.Fab")
		)
		(fp_line
			(start -0.12065 -0.305054)
			(end -0.12065 -0.2794)
			(stroke
				(width 0.1)
				(type default)
			)
			(layer "F.Fab")
		)
		(fp_line
			(start -0.12065 -0.2794)
			(end 0.12065 -0.2794)
			(stroke
				(width 0.1)
				(type default)
			)
			(layer "F.Fab")
		)
		(fp_line
			(start -0.12065 0.2794)
			(end -0.12065 0.3048)
			(stroke
				(width 0.1)
				(type default)
			)
			(layer "F.Fab")
		)
		(fp_line
			(start -0.12065 0.3048)
			(end -0.67945 0.3048)
			(stroke
				(width 0.1)
				(type default)
			)
			(layer "F.Fab")
		)
		(fp_line
			(start 0.120396 0.2794)
			(end -0.12065 0.2794)
			(stroke
				(width 0.1)
				(type default)
			)
			(layer "F.Fab")
		)
		(fp_line
			(start 0.120396 0.3048)
			(end 0.120396 0.2794)
			(stroke
				(width 0.1)
				(type default)
			)
			(layer "F.Fab")
		)
		(fp_line
			(start 0.12065 -0.3048)
			(end 0.67945 -0.3048)
			(stroke
				(width 0.1)
				(type default)
			)
			(layer "F.Fab")
		)
		(fp_line
			(start 0.12065 -0.2794)
			(end 0.12065 -0.3048)
			(stroke
				(width 0.1)
				(type default)
			)
			(layer "F.Fab")
		)
		(fp_line
			(start 0.67945 -0.3048)
			(end 0.67945 0.3048)
			(stroke
				(width 0.1)
				(type default)
			)
			(layer "F.Fab")
		)
		(fp_line
			(start 0.67945 0.3048)
			(end 0.120396 0.3048)
			(stroke
				(width 0.1)
				(type default)
			)
			(layer "F.Fab")
		)
		(pad "1" smd circle
			(at -0.40005 0)
			(size 0 0)
			(layers "F.Cu" "F.Mask" "F.Paste")
			(net "RST_SSD_LED_IOEXP_R_N")
		)
		(pad "2" smd circle
			(at 0.40005 0)
			(size 0 0)
			(layers "F.Cu" "F.Mask" "F.Paste")
			(net "RST_SSD_LED_IOEXP_N")
		)
	)
	(footprint ""
		(layer "F.Cu")
		(at 372.642384 -250.070874 -90)
		(property "Reference" "R1414"
			(at 0 0 270)
			(layer "F.SilkS")
			(hide yes)
			(effects
				(font
					(size 1.27 1.27)
				)
			)
		)
		(property "Value" ""
			(at 0 0 270)
			(layer "F.Fab")
			(effects
				(font
					(size 1.27 1.27)
				)
			)
		)
		(duplicate_pad_numbers_are_jumpers no)
		(fp_line
			(start -0.7874 0.4064)
			(end -0.7874 -0.4064)
			(stroke
				(width 0.1524)
				(type default)
			)
			(layer "F.SilkS")
		)
		(fp_line
			(start 0.7874 0.4064)
			(end -0.7874 0.4064)
			(stroke
				(width 0.1524)
				(type default)
			)
			(layer "F.SilkS")
		)
		(fp_line
			(start -0.7874 -0.4064)
			(end 0.7874 -0.4064)
			(stroke
				(width 0.1524)
				(type default)
			)
			(layer "F.SilkS")
		)
		(fp_line
			(start 0.7874 -0.4064)
			(end 0.7874 0.4064)
			(stroke
				(width 0.1524)
				(type default)
			)
			(layer "F.SilkS")
		)
		(fp_line
			(start -0.67945 0.3048)
			(end -0.67945 -0.305054)
			(stroke
				(width 0.1)
				(type default)
			)
			(layer "F.Fab")
		)
		(fp_line
			(start -0.12065 0.3048)
			(end -0.67945 0.3048)
			(stroke
				(width 0.1)
				(type default)
			)
			(layer "F.Fab")
		)
		(fp_line
			(start 0.120396 0.3048)
			(end 0.120396 0.2794)
			(stroke
				(width 0.1)
				(type default)
			)
			(layer "F.Fab")
		)
		(fp_line
			(start 0.67945 0.3048)
			(end 0.120396 0.3048)
			(stroke
				(width 0.1)
				(type default)
			)
			(layer "F.Fab")
		)
		(fp_line
			(start -0.12065 0.2794)
			(end -0.12065 0.3048)
			(stroke
				(width 0.1)
				(type default)
			)
			(layer "F.Fab")
		)
		(fp_line
			(start 0.120396 0.2794)
			(end -0.12065 0.2794)
			(stroke
				(width 0.1)
				(type default)
			)
			(layer "F.Fab")
		)
		(fp_line
			(start -0.12065 -0.2794)
			(end 0.12065 -0.2794)
			(stroke
				(width 0.1)
				(type default)
			)
			(layer "F.Fab")
		)
		(fp_line
			(start 0.12065 -0.2794)
			(end 0.12065 -0.3048)
			(stroke
				(width 0.1)
				(type default)
			)
			(layer "F.Fab")
		)
		(fp_line
			(start 0.12065 -0.3048)
			(end 0.67945 -0.3048)
			(stroke
				(width 0.1)
				(type default)
			)
			(layer "F.Fab")
		)
		(fp_line
			(start 0.67945 -0.3048)
			(end 0.67945 0.3048)
			(stroke
				(width 0.1)
				(type default)
			)
			(layer "F.Fab")
		)
		(fp_line
			(start -0.67945 -0.305054)
			(end -0.12065 -0.305054)
			(stroke
				(width 0.1)
				(type default)
			)
			(layer "F.Fab")
		)
		(fp_line
			(start -0.12065 -0.305054)
			(end -0.12065 -0.2794)
			(stroke
				(width 0.1)
				(type default)
			)
			(layer "F.Fab")
		)
		(pad "1" smd circle
			(at -0.40005 0 270)
			(size 0 0)
			(layers "F.Cu" "F.Mask" "F.Paste")
			(net "PEX3_MODE_SEL9")
		)
		(pad "2" smd circle
			(at 0.40005 0 270)
			(size 0 0)
			(layers "F.Cu" "F.Mask" "F.Paste")
			(net "P1V8_PEX")
		)
	)
	(footprint ""
		(layer "F.Cu")
		(at 461.011524 -553.91304 180)
		(property "Reference" "SCREW_SSD14_1"
			(at -5.6007 -1.402334 0)
			(unlocked yes)
			(layer "B.SilkS")
			(effects
				(font
					(size 0.7874 0.5842)
					(thickness 0.1524)
				)
				(justify mirror)
			)
		)
		(property "Value" ""
			(at 0 0 180)
			(layer "F.Fab")
			(effects
				(font
					(size 1.27 1.27)
				)
			)
		)
		(duplicate_pad_numbers_are_jumpers no)
		(pad "1" thru_hole circle
			(at 0 0 180)
			(size 0.4572 0.4572)
			(drill 0.2032)
			(layers "*.Cu" "*.Mask")
			(remove_unused_layers no)
			(net "Net_9146")
			(clearance 0.127)
			(thermal_gap 0.127)
			(padstack
				(mode front_inner_back)
				(layer "Inner"
					(shape circle)
					(size 0.4572 0.4572)
					(clearance 0.127)
				)
				(layer "B.Cu"
					(shape circle)
					(size 0.508 0.508)
					(clearance 0.1016)
				)
			)
		)
	)
)
